INTEGER-PLACES         2
DECIMAL-PLACES         5
X-OFFSET               0.000000
Y-OFFSET               0.000000
FEEDRATE               1
COORDINATES            ABSOLUTE
OUTPUT-UNITS           ENGLISH
TOOL-ORDER             INCREASING
REPEAT-CODES           NO
SUPPRESS-LEAD-ZEROES   NO
SUPPRESS-TRAIL-ZEROES  NO
SUPPRESS-EQUAL         NO
TOOL-SELECT            NO
OPTIMIZE_DRILLING      NO
ENHANCED_EXCELLON      NO
HEADER                 none
LEADER                 12
CODE                   ASCII
SEPARATE               NO
DRILLING               LAYER-PAIR
BACKDRILL              NO
